(kicad_pcb
	(version 20241229)
	(generator "pcbnew")
	(generator_version "9.0")
	(general
		(thickness 1.62)
		(legacy_teardrops no)
	)
	(paper "A3")
	(title_block
		(title "COM Express 7 Baseboard")
		(date "2025-02-04")
		(rev "1.1.2")
		(company "Antmicro Ltd")
		(comment 1 "www.antmicro.com")
		(comment 9 "footprints 366-371 of 802")
	)
	(layers
		(0 "F.Cu" signal)
		(4 "In1.Cu" signal)
		(6 "In2.Cu" signal)
		(8 "In3.Cu" signal)
		(10 "In4.Cu" signal)
		(12 "In5.Cu" signal)
		(14 "In6.Cu" signal)
		(2 "B.Cu" signal)
		(9 "F.Adhes" user "F.Adhesive")
		(11 "B.Adhes" user "B.Adhesive")
		(13 "F.Paste" user)
		(15 "B.Paste" user)
		(5 "F.SilkS" user "F.Silkscreen")
		(7 "B.SilkS" user "B.Silkscreen")
		(1 "F.Mask" user)
		(3 "B.Mask" user)
		(17 "Dwgs.User" user "User.Drawings")
		(19 "Cmts.User" user "User.Comments")
		(21 "Eco1.User" user "User.Eco1")
		(23 "Eco2.User" user "User.Eco2")
		(25 "Edge.Cuts" user)
		(27 "Margin" user)
		(31 "F.CrtYd" user "F.Courtyard")
		(29 "B.CrtYd" user "B.Courtyard")
		(35 "F.Fab" user)
		(33 "B.Fab" user)
	)
	(footprint "antmicro-footprints:R_0201"
		(layer "F.Cu")
		(at 128.41 147.31 -90)
		(descr "Resistor SMD 0201")
		(tags "resistor SMD 0201")
		(property "Reference" "R308"
			(at 4.099 -0.29 270)
			(layer "F.SilkS")
			(effects
				(font
					(size 0.7 0.7)
					(thickness 0.15)
				)
				(justify left bottom)
			)
		)
		(property "Value" "R_0R_0201"
			(at 0 1.25 270)
			(layer "F.Fab")
			(effects
				(font
					(size 0.7 0.7)
					(thickness 0.15)
				)
				(justify left bottom)
			)
		)
		(property "Datasheet" "https://www.bourns.com/docs/product-datasheets/cr.pdf"
			(at 0 0 270)
			(layer "F.Fab")
			(hide yes)
			(effects
				(font
					(size 1.27 1.27)
					(thickness 0.15)
				)
			)
		)
		(property "Author" "Antmicro"
			(at -18.9 275.72 0)
			(layer "F.Fab")
			(hide yes)
			(effects
				(font
					(size 1 1)
					(thickness 0.15)
				)
			)
		)
		(property "License" "Apache-2.0"
			(at -18.9 275.72 0)
			(layer "F.Fab")
			(hide yes)
			(effects
				(font
					(size 1 1)
					(thickness 0.15)
				)
			)
		)
		(property "MPN" "CR0201-FX-0R00GLF"
			(at -18.9 275.72 0)
			(layer "F.Fab")
			(hide yes)
			(effects
				(font
					(size 1 1)
					(thickness 0.15)
				)
			)
		)
		(property "Manufacturer" "Bourns"
			(at -18.9 275.72 0)
			(layer "F.Fab")
			(hide yes)
			(effects
				(font
					(size 1 1)
					(thickness 0.15)
				)
			)
		)
		(property "Tolerance" "1%"
			(at -18.9 275.72 0)
			(layer "F.Fab")
			(hide yes)
			(effects
				(font
					(size 1 1)
					(thickness 0.15)
				)
			)
		)
		(property "Val" "0R"
			(at -18.9 275.72 0)
			(layer "F.Fab")
			(hide yes)
			(effects
				(font
					(size 1 1)
					(thickness 0.15)
				)
			)
		)
		(sheetname "KR to SFI #2")
		(sheetfile "kr_sfi.kicad_sch")
		(attr smd)
		(fp_rect
			(start -0.7 -0.35)
			(end 0.7 0.35)
			(stroke
				(width 0.05)
				(type default)
			)
			(fill no)
			(layer "F.CrtYd")
		)
		(fp_rect
			(start -0.3 -0.15)
			(end 0.298 0.148)
			(stroke
				(width 0.15)
				(type solid)
			)
			(fill no)
			(layer "F.Fab")
		)
		(pad "" smd roundrect
			(at -0.346 0 270)
			(size 0.318 0.36)
			(layers "F.Paste")
			(roundrect_rratio 0.25)
			(teardrops
				(best_length_ratio 0.2)
				(max_length 1)
				(best_width_ratio 0.9)
				(max_width 2)
				(curved_edges yes)
				(filter_ratio 0.9)
				(enabled yes)
				(allow_two_segments yes)
				(prefer_zone_connections yes)
			)
		)
		(pad "" smd roundrect
			(at 0.344 0 270)
			(size 0.318 0.36)
			(layers "F.Paste")
			(roundrect_rratio 0.25)
			(teardrops
				(best_length_ratio 0.2)
				(max_length 1)
				(best_width_ratio 0.9)
				(max_width 2)
				(curved_edges yes)
				(filter_ratio 0.9)
				(enabled yes)
				(allow_two_segments yes)
				(prefer_zone_connections yes)
			)
		)
		(pad "1" smd roundrect
			(at -0.32 0 270)
			(size 0.46 0.4)
			(layers "F.Cu" "F.Mask")
			(roundrect_rratio 0.25)
			(net 952 "/2xSFP+/KR to SFI #2/SFI_R.TX-")
			(pintype "passive")
			(teardrops
				(best_length_ratio 0.2)
				(max_length 1)
				(best_width_ratio 0.9)
				(max_width 2)
				(curved_edges yes)
				(filter_ratio 0.9)
				(enabled yes)
				(allow_two_segments yes)
				(prefer_zone_connections yes)
			)
		)
		(pad "2" smd roundrect
			(at 0.32 0 270)
			(size 0.46 0.4)
			(layers "F.Cu" "F.Mask")
			(roundrect_rratio 0.25)
			(net 880 "/2xSFP+/SFI1.TX-")
			(pintype "passive")
			(teardrops
				(best_length_ratio 0.2)
				(max_length 1)
				(best_width_ratio 0.9)
				(max_width 2)
				(curved_edges yes)
				(filter_ratio 0.9)
				(enabled yes)
				(allow_two_segments yes)
				(prefer_zone_connections yes)
			)
		)
	)
	(footprint "antmicro-footprints:C_0603_1608Metric"
		(layer "F.Cu")
		(at 314.224999 118.96 -90)
		(descr "Capacitor SMD 0603")
		(tags "capacitor 0603")
		(property "Reference" "C42"
			(at -3.35 -0.425001 90)
			(layer "F.SilkS")
			(effects
				(font
					(size 0.7 0.7)
					(thickness 0.15)
				)
				(justify right bottom)
			)
		)
		(property "Value" "C_22u_16V_0603"
			(at -1.42757 1.770288 90)
			(layer "F.Fab")
			(effects
				(font
					(size 0.7 0.7)
					(thickness 0.15)
				)
				(justify right bottom)
			)
		)
		(property "Datasheet" "https://product.samsungsem.com/mlcc/CL10A226MO7JZN.do"
			(at 0 0 270)
			(layer "F.Fab")
			(hide yes)
			(effects
				(font
					(size 1.27 1.27)
					(thickness 0.15)
				)
			)
		)
		(property "Author" "Antmicro"
			(at 195.264999 433.184999 0)
			(layer "F.Fab")
			(hide yes)
			(effects
				(font
					(size 1 1)
					(thickness 0.15)
				)
			)
		)
		(property "Dielectric" ""
			(at 195.264999 433.184999 0)
			(layer "F.Fab")
			(hide yes)
			(effects
				(font
					(size 1 1)
					(thickness 0.15)
				)
			)
		)
		(property "License" "Apache-2.0"
			(at 195.264999 433.184999 0)
			(layer "F.Fab")
			(hide yes)
			(effects
				(font
					(size 1 1)
					(thickness 0.15)
				)
			)
		)
		(property "MPN" "CL10A226MO7JZNC"
			(at 195.264999 433.184999 0)
			(layer "F.Fab")
			(hide yes)
			(effects
				(font
					(size 1 1)
					(thickness 0.15)
				)
			)
		)
		(property "Manufacturer" "Samsung Electro-Mechanics"
			(at 195.264999 433.184999 0)
			(layer "F.Fab")
			(hide yes)
			(effects
				(font
					(size 1 1)
					(thickness 0.15)
				)
			)
		)
		(property "Public" "False"
			(at 195.264999 433.184999 0)
			(layer "F.Fab")
			(hide yes)
			(effects
				(font
					(size 1 1)
					(thickness 0.15)
				)
			)
		)
		(property "Val" "22u"
			(at 195.264999 433.184999 0)
			(layer "F.Fab")
			(hide yes)
			(effects
				(font
					(size 1 1)
					(thickness 0.15)
				)
			)
		)
		(property "Voltage" "16V"
			(at 195.264999 433.184999 0)
			(layer "F.Fab")
			(hide yes)
			(effects
				(font
					(size 1 1)
					(thickness 0.15)
				)
			)
		)
		(sheetname "Power")
		(sheetfile "power.kicad_sch")
		(attr smd)
		(fp_line
			(start -0.15 0.4)
			(end 0.15 0.4)
			(stroke
				(width 0.15)
				(type solid)
			)
			(layer "F.SilkS")
		)
		(fp_line
			(start -0.15 -0.4)
			(end 0.15 -0.4)
			(stroke
				(width 0.15)
				(type solid)
			)
			(layer "F.SilkS")
		)
		(fp_rect
			(start -1.25 -0.65)
			(end 1.25 0.65)
			(stroke
				(width 0.05)
				(type solid)
			)
			(fill no)
			(layer "F.CrtYd")
		)
		(fp_rect
			(start -0.8 -0.4)
			(end 0.8 0.4)
			(stroke
				(width 0.15)
				(type solid)
			)
			(fill no)
			(layer "F.Fab")
		)
		(pad "1" smd roundrect
			(at -0.7 0 270)
			(size 0.8 1)
			(layers "F.Cu" "F.Mask" "F.Paste")
			(roundrect_rratio 0.2)
			(net 1 "GND")
			(pintype "passive")
			(teardrops
				(best_length_ratio 0.2)
				(max_length 1)
				(best_width_ratio 0.9)
				(max_width 2)
				(curved_edges yes)
				(filter_ratio 0.9)
				(enabled yes)
				(allow_two_segments yes)
				(prefer_zone_connections yes)
			)
		)
		(pad "2" smd roundrect
			(at 0.7 0 270)
			(size 0.8 1)
			(layers "F.Cu" "F.Mask" "F.Paste")
			(roundrect_rratio 0.2)
			(net 62 "+12V_AON")
			(pintype "passive")
			(teardrops
				(best_length_ratio 0.2)
				(max_length 1)
				(best_width_ratio 0.9)
				(max_width 2)
				(curved_edges yes)
				(filter_ratio 0.9)
				(enabled yes)
				(allow_two_segments yes)
				(prefer_zone_connections yes)
			)
		)
	)
	(footprint "antmicro-footprints:R_0402_1005Metric"
		(layer "F.Cu")
		(at 136.6 101.41 180)
		(descr "Resistor SMD 0402")
		(tags "resistor SMD 0402")
		(property "Reference" "R17"
			(at -1.1 -1.4 0)
			(layer "F.SilkS")
			(effects
				(font
					(size 0.7 0.7)
					(thickness 0.15)
				)
				(justify right bottom)
			)
		)
		(property "Value" "R_75R_0402"
			(at -1.011843 1.772047 0)
			(layer "F.Fab")
			(effects
				(font
					(size 0.7 0.7)
					(thickness 0.15)
				)
				(justify right bottom)
			)
		)
		(property "Datasheet" "https://www.bourns.com/docs/product-datasheets/cr.pdf"
			(at 0 0 180)
			(layer "F.Fab")
			(hide yes)
			(effects
				(font
					(size 1.27 1.27)
					(thickness 0.15)
				)
			)
		)
		(property "Author" "Antmicro"
			(at 273.2 202.82 0)
			(layer "F.Fab")
			(hide yes)
			(effects
				(font
					(size 1 1)
					(thickness 0.15)
				)
			)
		)
		(property "License" "Apache-2.0"
			(at 273.2 202.82 0)
			(layer "F.Fab")
			(hide yes)
			(effects
				(font
					(size 1 1)
					(thickness 0.15)
				)
			)
		)
		(property "MPN" "CR0402-FX-75R0GLF"
			(at 273.2 202.82 0)
			(layer "F.Fab")
			(hide yes)
			(effects
				(font
					(size 1 1)
					(thickness 0.15)
				)
			)
		)
		(property "Manufacturer" "Bourns"
			(at 273.2 202.82 0)
			(layer "F.Fab")
			(hide yes)
			(effects
				(font
					(size 1 1)
					(thickness 0.15)
				)
			)
		)
		(property "Public" "False"
			(at 273.2 202.82 0)
			(layer "F.Fab")
			(hide yes)
			(effects
				(font
					(size 1 1)
					(thickness 0.15)
				)
			)
		)
		(property "Tolerance" "1%"
			(at 273.2 202.82 0)
			(layer "F.Fab")
			(hide yes)
			(effects
				(font
					(size 1 1)
					(thickness 0.15)
				)
			)
		)
		(property "Val" "75R"
			(at 273.2 202.82 0)
			(layer "F.Fab")
			(hide yes)
			(effects
				(font
					(size 1 1)
					(thickness 0.15)
				)
			)
		)
		(sheetname "2xUSB3.0+RJ45")
		(sheetfile "usb3+rj45.kicad_sch")
		(attr smd)
		(fp_rect
			(start -0.925 -0.47)
			(end 0.925 0.47)
			(stroke
				(width 0.05)
				(type default)
			)
			(fill no)
			(layer "F.CrtYd")
		)
		(fp_rect
			(start -0.5 -0.25)
			(end 0.5 0.25)
			(stroke
				(width 0.15)
				(type solid)
			)
			(fill no)
			(layer "F.Fab")
		)
		(pad "1" smd roundrect
			(at -0.48 0 180)
			(size 0.59 0.64)
			(layers "F.Cu" "F.Mask" "F.Paste")
			(roundrect_rratio 0.25)
			(net 50 "Net-(C12-Pad2)")
			(pintype "passive")
			(teardrops
				(best_length_ratio 0.2)
				(max_length 1)
				(best_width_ratio 0.9)
				(max_width 2)
				(curved_edges yes)
				(filter_ratio 0.9)
				(enabled yes)
				(allow_two_segments yes)
				(prefer_zone_connections yes)
			)
		)
		(pad "2" smd roundrect
			(at 0.48 0 180)
			(size 0.59 0.64)
			(layers "F.Cu" "F.Mask" "F.Paste")
			(roundrect_rratio 0.25)
			(net 552 "Net-(R17-Pad2)")
			(pintype "passive")
			(teardrops
				(best_length_ratio 0.2)
				(max_length 1)
				(best_width_ratio 0.9)
				(max_width 2)
				(curved_edges yes)
				(filter_ratio 0.9)
				(enabled yes)
				(allow_two_segments yes)
				(prefer_zone_connections yes)
			)
		)
	)
	(footprint "antmicro-footprints:R_0402_1005Metric"
		(layer "F.Cu")
		(at 114.4 150.36 -90)
		(descr "Resistor SMD 0402")
		(tags "resistor SMD 0402")
		(property "Reference" "R208"
			(at -0.46 -4.5 90)
			(layer "F.SilkS")
			(effects
				(font
					(size 0.7 0.7)
					(thickness 0.15)
				)
				(justify right bottom)
			)
		)
		(property "Value" "R_1k_0402"
			(at -1.011843 1.772047 90)
			(layer "F.Fab")
			(effects
				(font
					(size 0.7 0.7)
					(thickness 0.15)
				)
				(justify right bottom)
			)
		)
		(property "Datasheet" "https://www.bourns.com/docs/product-datasheets/cr.pdf"
			(at 0 0 270)
			(layer "F.Fab")
			(hide yes)
			(effects
				(font
					(size 1.27 1.27)
					(thickness 0.15)
				)
			)
		)
		(property "Author" "Antmicro"
			(at -35.96 264.76 0)
			(layer "F.Fab")
			(hide yes)
			(effects
				(font
					(size 1 1)
					(thickness 0.15)
				)
			)
		)
		(property "License" "Apache-2.0"
			(at -35.96 264.76 0)
			(layer "F.Fab")
			(hide yes)
			(effects
				(font
					(size 1 1)
					(thickness 0.15)
				)
			)
		)
		(property "MPN" "CR0402-FX-1001GLF"
			(at -35.96 264.76 0)
			(layer "F.Fab")
			(hide yes)
			(effects
				(font
					(size 1 1)
					(thickness 0.15)
				)
			)
		)
		(property "Manufacturer" "Bourns"
			(at -35.96 264.76 0)
			(layer "F.Fab")
			(hide yes)
			(effects
				(font
					(size 1 1)
					(thickness 0.15)
				)
			)
		)
		(property "Public" "False"
			(at -35.96 264.76 0)
			(layer "F.Fab")
			(hide yes)
			(effects
				(font
					(size 1 1)
					(thickness 0.15)
				)
			)
		)
		(property "Tolerance" "1%"
			(at -35.96 264.76 0)
			(layer "F.Fab")
			(hide yes)
			(effects
				(font
					(size 1 1)
					(thickness 0.15)
				)
			)
		)
		(property "Val" "1k"
			(at -35.96 264.76 0)
			(layer "F.Fab")
			(hide yes)
			(effects
				(font
					(size 1 1)
					(thickness 0.15)
				)
			)
		)
		(sheetname "PCIe redriver")
		(sheetfile "pcie_redriver.kicad_sch")
		(attr smd dnp)
		(fp_rect
			(start -0.925 -0.47)
			(end 0.925 0.47)
			(stroke
				(width 0.05)
				(type default)
			)
			(fill no)
			(layer "F.CrtYd")
		)
		(fp_rect
			(start -0.5 -0.25)
			(end 0.5 0.25)
			(stroke
				(width 0.15)
				(type solid)
			)
			(fill no)
			(layer "F.Fab")
		)
		(pad "1" smd roundrect
			(at -0.48 0 270)
			(size 0.59 0.64)
			(layers "F.Cu" "F.Mask" "F.Paste")
			(roundrect_rratio 0.25)
			(net 2 "+3V3")
			(pintype "passive")
			(teardrops
				(best_length_ratio 0.2)
				(max_length 1)
				(best_width_ratio 0.9)
				(max_width 2)
				(curved_edges yes)
				(filter_ratio 0.9)
				(enabled yes)
				(allow_two_segments yes)
				(prefer_zone_connections yes)
			)
		)
		(pad "2" smd roundrect
			(at 0.48 0 270)
			(size 0.59 0.64)
			(layers "F.Cu" "F.Mask" "F.Paste")
			(roundrect_rratio 0.25)
			(net 626 "/PCIe redriver/TX_FG0")
			(pintype "passive")
			(teardrops
				(best_length_ratio 0.2)
				(max_length 1)
				(best_width_ratio 0.9)
				(max_width 2)
				(curved_edges yes)
				(filter_ratio 0.9)
				(enabled yes)
				(allow_two_segments yes)
				(prefer_zone_connections yes)
			)
		)
	)
	(footprint "antmicro-footprints:TP_SMD_0.75mm"
		(layer "F.Cu")
		(at 156.35 129.56)
		(property "Reference" "TP69"
			(at 0.45 -1.25 90)
			(layer "F.SilkS")
			(effects
				(font
					(size 0.7 0.7)
					(thickness 0.15)
				)
				(justify left bottom)
			)
		)
		(property "Value" "TP_0.75mm_SMD"
			(at 0 1.2 0)
			(layer "F.Fab")
			(effects
				(font
					(size 0.7 0.7)
					(thickness 0.15)
				)
				(justify left bottom)
			)
		)
		(property "Author" "Antmicro"
			(at 0 0 0)
			(layer "F.Fab")
			(hide yes)
			(effects
				(font
					(size 1 1)
					(thickness 0.15)
				)
			)
		)
		(property "License" "Apache-2.0"
			(at 0 0 0)
			(layer "F.Fab")
			(hide yes)
			(effects
				(font
					(size 1 1)
					(thickness 0.15)
				)
			)
		)
		(property "MPN" ""
			(at 0 0 0)
			(layer "F.Fab")
			(hide yes)
			(effects
				(font
					(size 1 1)
					(thickness 0.15)
				)
			)
		)
		(property "Manufacturer" ""
			(at 0 0 0)
			(layer "F.Fab")
			(hide yes)
			(effects
				(font
					(size 1 1)
					(thickness 0.15)
				)
			)
		)
		(property "Public" "False"
			(at 0 0 0)
			(layer "F.Fab")
			(hide yes)
			(effects
				(font
					(size 1 1)
					(thickness 0.15)
				)
			)
		)
		(sheetname "KR to SFI #1")
		(sheetfile "kr_sfi.kicad_sch")
		(attr exclude_from_pos_files exclude_from_bom)
		(fp_circle
			(center 0 0)
			(end 0.475 0)
			(stroke
				(width 0.05)
				(type default)
			)
			(fill no)
			(layer "F.CrtYd")
		)
		(pad "1" smd circle
			(at 0 0)
			(size 0.75 0.75)
			(layers "F.Cu" "F.Mask")
			(net 732 "Net-(U43C-CLKOUTB+)")
			(pinfunction "1")
			(pintype "passive")
			(teardrops
				(best_length_ratio 0.4)
				(max_length 1)
				(best_width_ratio 0.9)
				(max_width 2)
				(curved_edges yes)
				(filter_ratio 0.9)
				(enabled yes)
				(allow_two_segments yes)
				(prefer_zone_connections yes)
			)
		)
	)
	(footprint "antmicro-footprints:TP_SMD_0.75mm"
		(layer "F.Cu")
		(at 153.75 129.56)
		(property "Reference" "TP61"
			(at 0.45 -1.25 90)
			(layer "F.SilkS")
			(effects
				(font
					(size 0.7 0.7)
					(thickness 0.15)
				)
				(justify left bottom)
			)
		)
		(property "Value" "TP_0.75mm_SMD"
			(at 0 1.2 0)
			(layer "F.Fab")
			(effects
				(font
					(size 0.7 0.7)
					(thickness 0.15)
				)
				(justify left bottom)
			)
		)
		(property "Author" "Antmicro"
			(at 0 0 0)
			(layer "F.Fab")
			(hide yes)
			(effects
				(font
					(size 1 1)
					(thickness 0.15)
				)
			)
		)
		(property "License" "Apache-2.0"
			(at 0 0 0)
			(layer "F.Fab")
			(hide yes)
			(effects
				(font
					(size 1 1)
					(thickness 0.15)
				)
			)
		)
		(property "MPN" ""
			(at 0 0 0)
			(layer "F.Fab")
			(hide yes)
			(effects
				(font
					(size 1 1)
					(thickness 0.15)
				)
			)
		)
		(property "Manufacturer" ""
			(at 0 0 0)
			(layer "F.Fab")
			(hide yes)
			(effects
				(font
					(size 1 1)
					(thickness 0.15)
				)
			)
		)
		(property "Public" "False"
			(at 0 0 0)
			(layer "F.Fab")
			(hide yes)
			(effects
				(font
					(size 1 1)
					(thickness 0.15)
				)
			)
		)
		(sheetname "KR to SFI #1")
		(sheetfile "kr_sfi.kicad_sch")
		(attr exclude_from_pos_files exclude_from_bom)
		(fp_circle
			(center 0 0)
			(end 0.475 0)
			(stroke
				(width 0.05)
				(type default)
			)
			(fill no)
			(layer "F.CrtYd")
		)
		(pad "1" smd circle
			(at 0 0)
			(size 0.75 0.75)
			(layers "F.Cu" "F.Mask")
			(net 724 "/2xSFP+/KR to SFI #1/TMS")
			(pinfunction "1")
			(pintype "passive")
			(teardrops
				(best_length_ratio 0.4)
				(max_length 1)
				(best_width_ratio 0.9)
				(max_width 2)
				(curved_edges yes)
				(filter_ratio 0.9)
				(enabled yes)
				(allow_two_segments yes)
				(prefer_zone_connections yes)
			)
		)
	)
)
